(kicad_pcb
	(version 20260206)
	(generator "pcbnew")
	(generator_version "10.0")
	(general
		(thickness 1.6)
		(legacy_teardrops no)
	)
	(paper "A4")
	(title_block
		(title "03242023_DA0F0TMBIJ0_F0T_Motherboard_J_brd_V01_OCP.brd")
		(comment 1 "Grand Teton / footprint 1368 of 6105 (J13), pads 113-224 of 291")
	)
	(layers
		(0 "F.Cu" signal "TOP")
		(4 "In1.Cu" signal "GND")
		(6 "In2.Cu" signal "IN1")
		(8 "In3.Cu" signal "GND1")
		(10 "In4.Cu" signal "IN2")
		(12 "In5.Cu" signal "GND2")
		(14 "In6.Cu" signal "IN3")
		(16 "In7.Cu" signal "GND3")
		(18 "In8.Cu" signal "VCC")
		(20 "In9.Cu" signal "VCC1")
		(22 "In10.Cu" signal "GND4")
		(24 "In11.Cu" signal "IN4")
		(26 "In12.Cu" signal "GND5")
		(28 "In13.Cu" signal "IN5")
		(30 "In14.Cu" signal "GND6")
		(32 "In15.Cu" signal "IN6")
		(34 "In16.Cu" signal "GND7")
		(2 "B.Cu" signal "BOTTOM")
		(9 "F.Adhes" user "F.Adhesive")
		(11 "B.Adhes" user "B.Adhesive")
		(13 "F.Paste" user "Package Geometry/Pastemask Top")
		(15 "B.Paste" user "Package Geometry/Pastemask Bottom")
		(5 "F.SilkS" user "Ref Des/Silkscreen Top")
		(7 "B.SilkS" user "Ref Des/Silkscreen Bottom")
		(1 "F.Mask" user "Board Geometry/Soldermask Top")
		(3 "B.Mask" user "Board Geometry/Soldermask Bottom")
		(17 "Dwgs.User" user "User.Drawings")
		(19 "Cmts.User" user "User.Comments")
		(21 "Eco1.User" user "User.Eco1")
		(23 "Eco2.User" user "User.Eco2")
		(25 "Edge.Cuts" user "Board Geometry/Outline")
		(27 "Margin" user)
		(31 "F.CrtYd" user "Package Geometry/Place Bound Top")
		(29 "B.CrtYd" user "Package Geometry/Place Bound Bottom")
		(35 "F.Fab" user "Ref Des/Assembly Top")
		(33 "B.Fab" user "Ref Des/Assembly Bottom")
	)
	(footprint ""
		(layer "F.Cu")
		(at 446.522348 -258.091686)
		(property "Reference" "J13"
			(at -3.683 -81.702148 0)
			(unlocked yes)
			(layer "F.SilkS")
			(effects
				(font
					(size 0.7874 0.5842)
					(thickness 0.1524)
				)
				(justify left)
			)
		)
		(property "Value" ""
			(at 0 0 0)
			(layer "F.Fab")
			(effects
				(font
					(size 1.27 1.27)
				)
			)
		)
		(duplicate_pad_numbers_are_jumpers no)
		(pad "113" smd rect
			(at -2.050034 36.975034 270)
			(size 0.519938 1.4986)
			(layers "F.Cu" "F.Mask" "F.Paste")
			(net "M_G_CPU0_SB_DQ<9>")
		)
		(pad "114" smd rect
			(at -2.050034 37.824918 270)
			(size 0.519938 1.4986)
			(layers "F.Cu" "F.Mask" "F.Paste")
			(net "GND")
		)
		(pad "115" smd rect
			(at -2.050034 38.675056 270)
			(size 0.519938 1.4986)
			(layers "F.Cu" "F.Mask" "F.Paste")
			(net "M_G_CPU0_SB_DQS_DP<1>")
		)
		(pad "116" smd rect
			(at -2.050034 39.52494 270)
			(size 0.519938 1.4986)
			(layers "F.Cu" "F.Mask" "F.Paste")
			(net "M_G_CPU0_SB_DQS_DN<1>")
		)
		(pad "117" smd rect
			(at -2.050034 40.375078 270)
			(size 0.519938 1.4986)
			(layers "F.Cu" "F.Mask" "F.Paste")
			(net "GND")
		)
		(pad "118" smd rect
			(at -2.050034 41.224962 270)
			(size 0.519938 1.4986)
			(layers "F.Cu" "F.Mask" "F.Paste")
			(net "M_G_CPU0_SB_DQ<12>")
		)
		(pad "119" smd rect
			(at -2.050034 42.0751 270)
			(size 0.519938 1.4986)
			(layers "F.Cu" "F.Mask" "F.Paste")
			(net "GND")
		)
		(pad "120" smd rect
			(at -2.050034 42.924984 270)
			(size 0.519938 1.4986)
			(layers "F.Cu" "F.Mask" "F.Paste")
			(net "M_G_CPU0_SB_DQ<13>")
		)
		(pad "121" smd rect
			(at -2.050034 43.775122 270)
			(size 0.519938 1.4986)
			(layers "F.Cu" "F.Mask" "F.Paste")
			(net "GND")
		)
		(pad "122" smd rect
			(at -2.050034 44.625006 270)
			(size 0.519938 1.4986)
			(layers "F.Cu" "F.Mask" "F.Paste")
			(net "M_G_CPU0_SB_DQ<16>")
		)
		(pad "123" smd rect
			(at -2.050034 45.47489 270)
			(size 0.519938 1.4986)
			(layers "F.Cu" "F.Mask" "F.Paste")
			(net "GND")
		)
		(pad "124" smd rect
			(at -2.050034 46.325028 270)
			(size 0.519938 1.4986)
			(layers "F.Cu" "F.Mask" "F.Paste")
			(net "M_G_CPU0_SB_DQ<17>")
		)
		(pad "125" smd rect
			(at -2.050034 47.174912 270)
			(size 0.519938 1.4986)
			(layers "F.Cu" "F.Mask" "F.Paste")
			(net "GND")
		)
		(pad "126" smd rect
			(at -2.050034 48.02505 270)
			(size 0.519938 1.4986)
			(layers "F.Cu" "F.Mask" "F.Paste")
			(net "M_G_CPU0_SB_DQS_DP<2>")
		)
		(pad "127" smd rect
			(at -2.050034 48.874934 270)
			(size 0.519938 1.4986)
			(layers "F.Cu" "F.Mask" "F.Paste")
			(net "M_G_CPU0_SB_DQS_DN<2>")
		)
		(pad "128" smd rect
			(at -2.050034 49.725072 270)
			(size 0.519938 1.4986)
			(layers "F.Cu" "F.Mask" "F.Paste")
			(net "GND")
		)
		(pad "129" smd rect
			(at -2.050034 50.574956 270)
			(size 0.519938 1.4986)
			(layers "F.Cu" "F.Mask" "F.Paste")
			(net "M_G_CPU0_SB_DQ<20>")
		)
		(pad "130" smd rect
			(at -2.050034 51.425094 270)
			(size 0.519938 1.4986)
			(layers "F.Cu" "F.Mask" "F.Paste")
			(net "GND")
		)
		(pad "131" smd rect
			(at -2.050034 52.274978 270)
			(size 0.519938 1.4986)
			(layers "F.Cu" "F.Mask" "F.Paste")
			(net "M_G_CPU0_SB_DQ<21>")
		)
		(pad "132" smd rect
			(at -2.050034 53.125116 270)
			(size 0.519938 1.4986)
			(layers "F.Cu" "F.Mask" "F.Paste")
			(net "GND")
		)
		(pad "133" smd rect
			(at -2.050034 53.975 270)
			(size 0.519938 1.4986)
			(layers "F.Cu" "F.Mask" "F.Paste")
			(net "M_G_CPU0_SB_DQ<24>")
		)
		(pad "134" smd rect
			(at -2.050034 54.824884 270)
			(size 0.519938 1.4986)
			(layers "F.Cu" "F.Mask" "F.Paste")
			(net "GND")
		)
		(pad "135" smd rect
			(at -2.050034 55.675022 270)
			(size 0.519938 1.4986)
			(layers "F.Cu" "F.Mask" "F.Paste")
			(net "M_G_CPU0_SB_DQ<25>")
		)
		(pad "136" smd rect
			(at -2.050034 56.524906 270)
			(size 0.519938 1.4986)
			(layers "F.Cu" "F.Mask" "F.Paste")
			(net "GND")
		)
		(pad "137" smd rect
			(at -2.050034 57.375044 270)
			(size 0.519938 1.4986)
			(layers "F.Cu" "F.Mask" "F.Paste")
			(net "M_G_CPU0_SB_DQS_DP<3>")
		)
		(pad "138" smd rect
			(at -2.050034 58.224928 270)
			(size 0.519938 1.4986)
			(layers "F.Cu" "F.Mask" "F.Paste")
			(net "M_G_CPU0_SB_DQS_DN<3>")
		)
		(pad "139" smd rect
			(at -2.050034 59.075066 270)
			(size 0.519938 1.4986)
			(layers "F.Cu" "F.Mask" "F.Paste")
			(net "GND")
		)
		(pad "140" smd rect
			(at -2.050034 59.92495 270)
			(size 0.519938 1.4986)
			(layers "F.Cu" "F.Mask" "F.Paste")
			(net "M_G_CPU0_SB_DQ<28>")
		)
		(pad "141" smd rect
			(at -2.050034 60.775088 270)
			(size 0.519938 1.4986)
			(layers "F.Cu" "F.Mask" "F.Paste")
			(net "GND")
		)
		(pad "142" smd rect
			(at -2.050034 61.624972 270)
			(size 0.519938 1.4986)
			(layers "F.Cu" "F.Mask" "F.Paste")
			(net "M_G_CPU0_SB_DQ<29>")
		)
		(pad "143" smd rect
			(at -2.050034 62.47511 270)
			(size 0.519938 1.4986)
			(layers "F.Cu" "F.Mask" "F.Paste")
			(net "GND")
		)
		(pad "144" smd rect
			(at -2.050034 63.324994 270)
			(size 0.519938 1.4986)
			(layers "F.Cu" "F.Mask" "F.Paste")
			(net "TP_CHG_CPU0_DIMM1_FRU_1")
		)
		(pad "145" smd rect
			(at 2.050034 -63.324994 270)
			(size 0.519938 1.4986)
			(layers "F.Cu" "F.Mask" "F.Paste")
			(net "P12V_S3_AUX_CPU0_NVDIMM")
		)
		(pad "146" smd rect
			(at 2.050034 -62.47511 270)
			(size 0.519938 1.4986)
			(layers "F.Cu" "F.Mask" "F.Paste")
			(net "P12V_S3_AUX_CPU0_NVDIMM")
		)
		(pad "147" smd rect
			(at 2.050034 -61.624972 270)
			(size 0.519938 1.4986)
			(layers "F.Cu" "F.Mask" "F.Paste")
			(net "PWRGD_CHG_CPU0_DIMM1")
		)
		(pad "148" smd rect
			(at 2.050034 -60.775088 270)
			(size 0.519938 1.4986)
			(layers "F.Cu" "F.Mask" "F.Paste")
			(net "PD_CHG_CPU0_DIMM1_SAA")
		)
		(pad "149" smd rect
			(at 2.050034 -59.92495 270)
			(size 0.519938 1.4986)
			(layers "F.Cu" "F.Mask" "F.Paste")
			(net "TP_CHG_CPU0_DIMM1_FRU_2")
		)
		(pad "150" smd rect
			(at 2.050034 -59.075066 270)
			(size 0.519938 1.4986)
			(layers "F.Cu" "F.Mask" "F.Paste")
			(net "TP_CHG_CPU0_DIMM1_FRU_3")
		)
		(pad "151" smd rect
			(at 2.050034 -58.224928 270)
			(size 0.519938 1.4986)
			(layers "F.Cu" "F.Mask" "F.Paste")
			(net "GND")
		)
		(pad "152" smd rect
			(at 2.050034 -57.375044 270)
			(size 0.519938 1.4986)
			(layers "F.Cu" "F.Mask" "F.Paste")
			(net "M_G_CPU0_SA_DQ<2>")
		)
		(pad "153" smd rect
			(at 2.050034 -56.524906 270)
			(size 0.519938 1.4986)
			(layers "F.Cu" "F.Mask" "F.Paste")
			(net "GND")
		)
		(pad "154" smd rect
			(at 2.050034 -55.675022 270)
			(size 0.519938 1.4986)
			(layers "F.Cu" "F.Mask" "F.Paste")
			(net "M_G_CPU0_SA_DQ<3>")
		)
		(pad "155" smd rect
			(at 2.050034 -54.824884 270)
			(size 0.519938 1.4986)
			(layers "F.Cu" "F.Mask" "F.Paste")
			(net "GND")
		)
		(pad "156" smd rect
			(at 2.050034 -53.975 270)
			(size 0.519938 1.4986)
			(layers "F.Cu" "F.Mask" "F.Paste")
			(net "M_G_CPU0_SA_DQS_DN<5>")
		)
		(pad "157" smd rect
			(at 2.050034 -53.125116 270)
			(size 0.519938 1.4986)
			(layers "F.Cu" "F.Mask" "F.Paste")
			(net "M_G_CPU0_SA_DQS_DP<5>")
		)
		(pad "158" smd rect
			(at 2.050034 -52.274978 270)
			(size 0.519938 1.4986)
			(layers "F.Cu" "F.Mask" "F.Paste")
			(net "GND")
		)
		(pad "159" smd rect
			(at 2.050034 -51.425094 270)
			(size 0.519938 1.4986)
			(layers "F.Cu" "F.Mask" "F.Paste")
			(net "M_G_CPU0_SA_DQ<6>")
		)
		(pad "160" smd rect
			(at 2.050034 -50.574956 270)
			(size 0.519938 1.4986)
			(layers "F.Cu" "F.Mask" "F.Paste")
			(net "GND")
		)
		(pad "161" smd rect
			(at 2.050034 -49.725072 270)
			(size 0.519938 1.4986)
			(layers "F.Cu" "F.Mask" "F.Paste")
			(net "M_G_CPU0_SA_DQ<7>")
		)
		(pad "162" smd rect
			(at 2.050034 -48.874934 270)
			(size 0.519938 1.4986)
			(layers "F.Cu" "F.Mask" "F.Paste")
			(net "GND")
		)
		(pad "163" smd rect
			(at 2.050034 -48.02505 270)
			(size 0.519938 1.4986)
			(layers "F.Cu" "F.Mask" "F.Paste")
			(net "M_G_CPU0_SA_DQ<10>")
		)
		(pad "164" smd rect
			(at 2.050034 -47.174912 270)
			(size 0.519938 1.4986)
			(layers "F.Cu" "F.Mask" "F.Paste")
			(net "GND")
		)
		(pad "165" smd rect
			(at 2.050034 -46.325028 270)
			(size 0.519938 1.4986)
			(layers "F.Cu" "F.Mask" "F.Paste")
			(net "M_G_CPU0_SA_DQ<11>")
		)
		(pad "166" smd rect
			(at 2.050034 -45.47489 270)
			(size 0.519938 1.4986)
			(layers "F.Cu" "F.Mask" "F.Paste")
			(net "GND")
		)
		(pad "167" smd rect
			(at 2.050034 -44.625006 270)
			(size 0.519938 1.4986)
			(layers "F.Cu" "F.Mask" "F.Paste")
			(net "M_G_CPU0_SA_DQS_DN<6>")
		)
		(pad "168" smd rect
			(at 2.050034 -43.775122 270)
			(size 0.519938 1.4986)
			(layers "F.Cu" "F.Mask" "F.Paste")
			(net "M_G_CPU0_SA_DQS_DP<6>")
		)
		(pad "169" smd rect
			(at 2.050034 -42.924984 270)
			(size 0.519938 1.4986)
			(layers "F.Cu" "F.Mask" "F.Paste")
			(net "GND")
		)
		(pad "170" smd rect
			(at 2.050034 -42.0751 270)
			(size 0.519938 1.4986)
			(layers "F.Cu" "F.Mask" "F.Paste")
			(net "M_G_CPU0_SA_DQ<14>")
		)
		(pad "171" smd rect
			(at 2.050034 -41.224962 270)
			(size 0.519938 1.4986)
			(layers "F.Cu" "F.Mask" "F.Paste")
			(net "GND")
		)
		(pad "172" smd rect
			(at 2.050034 -40.375078 270)
			(size 0.519938 1.4986)
			(layers "F.Cu" "F.Mask" "F.Paste")
			(net "M_G_CPU0_SA_DQ<15>")
		)
		(pad "173" smd rect
			(at 2.050034 -39.52494 270)
			(size 0.519938 1.4986)
			(layers "F.Cu" "F.Mask" "F.Paste")
			(net "GND")
		)
		(pad "174" smd rect
			(at 2.050034 -38.675056 270)
			(size 0.519938 1.4986)
			(layers "F.Cu" "F.Mask" "F.Paste")
			(net "M_G_CPU0_SA_DQ<18>")
		)
		(pad "175" smd rect
			(at 2.050034 -37.824918 270)
			(size 0.519938 1.4986)
			(layers "F.Cu" "F.Mask" "F.Paste")
			(net "GND")
		)
		(pad "176" smd rect
			(at 2.050034 -36.975034 270)
			(size 0.519938 1.4986)
			(layers "F.Cu" "F.Mask" "F.Paste")
			(net "M_G_CPU0_SA_DQ<19>")
		)
		(pad "177" smd rect
			(at 2.050034 -36.124896 270)
			(size 0.519938 1.4986)
			(layers "F.Cu" "F.Mask" "F.Paste")
			(net "GND")
		)
		(pad "178" smd rect
			(at 2.050034 -35.275012 270)
			(size 0.519938 1.4986)
			(layers "F.Cu" "F.Mask" "F.Paste")
			(net "M_G_CPU0_SA_DQS_DN<7>")
		)
		(pad "179" smd rect
			(at 2.050034 -34.425128 270)
			(size 0.519938 1.4986)
			(layers "F.Cu" "F.Mask" "F.Paste")
			(net "M_G_CPU0_SA_DQS_DP<7>")
		)
		(pad "180" smd rect
			(at 2.050034 -33.57499 270)
			(size 0.519938 1.4986)
			(layers "F.Cu" "F.Mask" "F.Paste")
			(net "GND")
		)
		(pad "181" smd rect
			(at 2.050034 -32.725106 270)
			(size 0.519938 1.4986)
			(layers "F.Cu" "F.Mask" "F.Paste")
			(net "M_G_CPU0_SA_DQ<22>")
		)
		(pad "182" smd rect
			(at 2.050034 -31.874968 270)
			(size 0.519938 1.4986)
			(layers "F.Cu" "F.Mask" "F.Paste")
			(net "GND")
		)
		(pad "183" smd rect
			(at 2.050034 -31.025084 270)
			(size 0.519938 1.4986)
			(layers "F.Cu" "F.Mask" "F.Paste")
			(net "M_G_CPU0_SA_DQ<23>")
		)
		(pad "184" smd rect
			(at 2.050034 -30.174946 270)
			(size 0.519938 1.4986)
			(layers "F.Cu" "F.Mask" "F.Paste")
			(net "GND")
		)
		(pad "185" smd rect
			(at 2.050034 -29.325062 270)
			(size 0.519938 1.4986)
			(layers "F.Cu" "F.Mask" "F.Paste")
			(net "M_G_CPU0_SA_DQ<26>")
		)
		(pad "186" smd rect
			(at 2.050034 -28.474924 270)
			(size 0.519938 1.4986)
			(layers "F.Cu" "F.Mask" "F.Paste")
			(net "GND")
		)
		(pad "187" smd rect
			(at 2.050034 -27.62504 270)
			(size 0.519938 1.4986)
			(layers "F.Cu" "F.Mask" "F.Paste")
			(net "M_G_CPU0_SA_DQ<27>")
		)
		(pad "188" smd rect
			(at 2.050034 -26.774902 270)
			(size 0.519938 1.4986)
			(layers "F.Cu" "F.Mask" "F.Paste")
			(net "GND")
		)
		(pad "189" smd rect
			(at 2.050034 -25.925018 270)
			(size 0.519938 1.4986)
			(layers "F.Cu" "F.Mask" "F.Paste")
			(net "M_G_CPU0_SA_DQS_DN<8>")
		)
		(pad "190" smd rect
			(at 2.050034 -25.07488 270)
			(size 0.519938 1.4986)
			(layers "F.Cu" "F.Mask" "F.Paste")
			(net "M_G_CPU0_SA_DQS_DP<8>")
		)
		(pad "191" smd rect
			(at 2.050034 -24.224996 270)
			(size 0.519938 1.4986)
			(layers "F.Cu" "F.Mask" "F.Paste")
			(net "GND")
		)
		(pad "192" smd rect
			(at 2.050034 -23.375112 270)
			(size 0.519938 1.4986)
			(layers "F.Cu" "F.Mask" "F.Paste")
			(net "M_G_CPU0_SA_DQ<30>")
		)
		(pad "193" smd rect
			(at 2.050034 -22.524974 270)
			(size 0.519938 1.4986)
			(layers "F.Cu" "F.Mask" "F.Paste")
			(net "GND")
		)
		(pad "194" smd rect
			(at 2.050034 -21.67509 270)
			(size 0.519938 1.4986)
			(layers "F.Cu" "F.Mask" "F.Paste")
			(net "M_G_CPU0_SA_DQ<31>")
		)
		(pad "195" smd rect
			(at 2.050034 -20.824952 270)
			(size 0.519938 1.4986)
			(layers "F.Cu" "F.Mask" "F.Paste")
			(net "GND")
		)
		(pad "196" smd rect
			(at 2.050034 -19.975068 270)
			(size 0.519938 1.4986)
			(layers "F.Cu" "F.Mask" "F.Paste")
			(net "M_G_CPU0_SA_CB<2>")
		)
		(pad "197" smd rect
			(at 2.050034 -19.12493 270)
			(size 0.519938 1.4986)
			(layers "F.Cu" "F.Mask" "F.Paste")
			(net "GND")
		)
		(pad "198" smd rect
			(at 2.050034 -18.275046 270)
			(size 0.519938 1.4986)
			(layers "F.Cu" "F.Mask" "F.Paste")
			(net "M_G_CPU0_SA_CB<3>")
		)
		(pad "199" smd rect
			(at 2.050034 -17.424908 270)
			(size 0.519938 1.4986)
			(layers "F.Cu" "F.Mask" "F.Paste")
			(net "GND")
		)
		(pad "200" smd rect
			(at 2.050034 -16.575024 270)
			(size 0.519938 1.4986)
			(layers "F.Cu" "F.Mask" "F.Paste")
			(net "M_G_CPU0_SA_DQS_DN<9>")
		)
		(pad "201" smd rect
			(at 2.050034 -15.724886 270)
			(size 0.519938 1.4986)
			(layers "F.Cu" "F.Mask" "F.Paste")
			(net "M_G_CPU0_SA_DQS_DP<9>")
		)
		(pad "202" smd rect
			(at 2.050034 -14.875002 270)
			(size 0.519938 1.4986)
			(layers "F.Cu" "F.Mask" "F.Paste")
			(net "GND")
		)
		(pad "203" smd rect
			(at 2.050034 -14.025118 270)
			(size 0.519938 1.4986)
			(layers "F.Cu" "F.Mask" "F.Paste")
			(net "M_G_CPU0_SA_CB<6>")
		)
		(pad "204" smd rect
			(at 2.050034 -13.17498 270)
			(size 0.519938 1.4986)
			(layers "F.Cu" "F.Mask" "F.Paste")
			(net "GND")
		)
		(pad "205" smd rect
			(at 2.050034 -12.325096 270)
			(size 0.519938 1.4986)
			(layers "F.Cu" "F.Mask" "F.Paste")
			(net "M_G_CPU0_SA_CB<7>")
		)
		(pad "206" smd rect
			(at 2.050034 -11.474958 270)
			(size 0.519938 1.4986)
			(layers "F.Cu" "F.Mask" "F.Paste")
			(net "GND")
		)
		(pad "207" smd rect
			(at 2.050034 -10.625074 270)
			(size 0.519938 1.4986)
			(layers "F.Cu" "F.Mask" "F.Paste")
			(net "RST_M_GH_CPU0_FPGA_N")
		)
		(pad "208" smd rect
			(at 2.050034 -9.774936 270)
			(size 0.519938 1.4986)
			(layers "F.Cu" "F.Mask" "F.Paste")
			(net "GND")
		)
		(pad "209" smd rect
			(at 2.050034 -8.925052 270)
			(size 0.519938 1.4986)
			(layers "F.Cu" "F.Mask" "F.Paste")
			(net "M_G_CPU0_SA_CS_N<1>")
		)
		(pad "210" smd rect
			(at 2.050034 -8.074914 270)
			(size 0.519938 1.4986)
			(layers "F.Cu" "F.Mask" "F.Paste")
			(net "GND")
		)
		(pad "211" smd rect
			(at 2.050034 -7.22503 270)
			(size 0.519938 1.4986)
			(layers "F.Cu" "F.Mask" "F.Paste")
			(net "M_G_CPU0_SA_CA<1>")
		)
		(pad "212" smd rect
			(at 2.050034 -6.374892 270)
			(size 0.519938 1.4986)
			(layers "F.Cu" "F.Mask" "F.Paste")
			(net "GND")
		)
		(pad "213" smd rect
			(at 2.050034 -5.525008 270)
			(size 0.519938 1.4986)
			(layers "F.Cu" "F.Mask" "F.Paste")
			(net "M_G_CPU0_SA_CA<3>")
		)
		(pad "214" smd rect
			(at 2.050034 -4.675124 270)
			(size 0.519938 1.4986)
			(layers "F.Cu" "F.Mask" "F.Paste")
			(net "GND")
		)
		(pad "215" smd rect
			(at 2.050034 -3.824986 270)
			(size 0.519938 1.4986)
			(layers "F.Cu" "F.Mask" "F.Paste")
			(net "M_G_CPU0_SA_CA<5>")
		)
		(pad "216" smd rect
			(at 2.050034 -2.975102 270)
			(size 0.519938 1.4986)
			(layers "F.Cu" "F.Mask" "F.Paste")
			(net "GND")
		)
		(pad "217" smd rect
			(at 2.050034 -2.124964 270)
			(size 0.519938 1.4986)
			(layers "F.Cu" "F.Mask" "F.Paste")
			(net "M_G_CPU0_CLK_DP<0>")
		)
		(pad "218" smd rect
			(at 2.050034 -1.27508 270)
			(size 0.519938 1.4986)
			(layers "F.Cu" "F.Mask" "F.Paste")
			(net "M_G_CPU0_CLK_DN<0>")
		)
		(pad "219" smd rect
			(at 2.050034 -0.424942 270)
			(size 0.519938 1.4986)
			(layers "F.Cu" "F.Mask" "F.Paste")
			(net "GND")
		)
		(pad "220" smd rect
			(at 2.050034 5.525008 270)
			(size 0.519938 1.4986)
			(layers "F.Cu" "F.Mask" "F.Paste")
			(net "TP_CHG_CPU0_DIMM1_FRU_4")
		)
		(pad "221" smd rect
			(at 2.050034 6.374892 270)
			(size 0.519938 1.4986)
			(layers "F.Cu" "F.Mask" "F.Paste")
			(net "M_G_CPU0_SB_CA<1>")
		)
		(pad "222" smd rect
			(at 2.050034 7.22503 270)
			(size 0.519938 1.4986)
			(layers "F.Cu" "F.Mask" "F.Paste")
			(net "GND")
		)
		(pad "223" smd rect
			(at 2.050034 8.074914 270)
			(size 0.519938 1.4986)
			(layers "F.Cu" "F.Mask" "F.Paste")
			(net "M_G_CPU0_SB_CA<3>")
		)
		(pad "224" smd rect
			(at 2.050034 8.925052 270)
			(size 0.519938 1.4986)
			(layers "F.Cu" "F.Mask" "F.Paste")
			(net "GND")
		)
	)
)
